(kicad_pcb
	(version 20260206)
	(generator "pcbnew")
	(generator_version "10.0")
	(general
		(thickness 1.6)
		(legacy_teardrops no)
	)
	(paper "A4")
	(title_block
		(title "Wiwynn_Tioga_Pass_MB.brd")
		(comment 1 "Tioga Pass / footprint 3254 of 4770 (J6M1), pads 244-291 of 291")
	)
	(layers
		(0 "F.Cu" signal "TOP")
		(4 "In1.Cu" signal "L2GND")
		(6 "In2.Cu" signal "L3")
		(8 "In3.Cu" signal "L4GND")
		(10 "In4.Cu" signal "L5")
		(12 "In5.Cu" signal "L6GND")
		(14 "In6.Cu" signal "L7VCC")
		(16 "In7.Cu" signal "L8VCC")
		(18 "In8.Cu" signal "L9GND")
		(20 "In9.Cu" signal "L10")
		(22 "In10.Cu" signal "L11GND")
		(24 "In11.Cu" signal "L12")
		(26 "In12.Cu" signal "L13GND")
		(2 "B.Cu" signal "BOTTOM")
		(9 "F.Adhes" user "F.Adhesive")
		(11 "B.Adhes" user "B.Adhesive")
		(13 "F.Paste" user "Package Geometry/Pastemask Top")
		(15 "B.Paste" user "Package Geometry/Pastemask Bottom")
		(5 "F.SilkS" user "Ref Des/Silkscreen Top")
		(7 "B.SilkS" user "Ref Des/Silkscreen Bottom")
		(1 "F.Mask" user "Board Geometry/Soldermask Top")
		(3 "B.Mask" user "Board Geometry/Soldermask Bottom")
		(17 "Dwgs.User" user "User.Drawings")
		(19 "Cmts.User" user "User.Comments")
		(21 "Eco1.User" user "User.Eco1")
		(23 "Eco2.User" user "User.Eco2")
		(25 "Edge.Cuts" user "Board Geometry/Outline")
		(27 "Margin" user)
		(31 "F.CrtYd" user "Package Geometry/Place Bound Top")
		(29 "B.CrtYd" user "Package Geometry/Place Bound Bottom")
		(35 "F.Fab" user "Ref Des/Assembly Top")
		(33 "B.Fab" user "Ref Des/Assembly Bottom")
	)
	(footprint ""
		(layer "B.Cu")
		(at 194.700398 -132.876036 90)
		(property "Reference" "J6M1"
			(at 2.352548 37.96411 0)
			(unlocked yes)
			(layer "B.SilkS")
			(effects
				(font
					(size 0.7874 0.5842)
					(thickness 0.1524)
				)
				(justify left mirror)
			)
		)
		(property "Value" ""
			(at 0 0 90)
			(layer "B.Fab")
			(effects
				(font
					(size 1.27 1.27)
				)
				(justify mirror)
			)
		)
		(duplicate_pad_numbers_are_jumpers no)
		(pad "241" smd rect
			(at -4.59994 86.700106 270)
			(size 1.8034 0.508)
			(layers "B.Cu" "B.Mask" "B.Paste")
			(net "GND")
		)
		(pad "242" smd rect
			(at -4.59994 87.54999 270)
			(size 1.8034 0.508)
			(layers "B.Cu" "B.Mask" "B.Paste")
			(net "M_D_DQ<33>")
		)
		(pad "243" smd rect
			(at -4.59994 88.399874 270)
			(size 1.8034 0.508)
			(layers "B.Cu" "B.Mask" "B.Paste")
			(net "GND")
		)
		(pad "244" smd rect
			(at -4.59994 89.250012 270)
			(size 1.8034 0.508)
			(layers "B.Cu" "B.Mask" "B.Paste")
			(net "M_D_DQS_DN<4>")
		)
		(pad "245" smd rect
			(at -4.59994 90.099896 270)
			(size 1.8034 0.508)
			(layers "B.Cu" "B.Mask" "B.Paste")
			(net "M_D_DQS_DP<4>")
		)
		(pad "246" smd rect
			(at -4.59994 90.950034 270)
			(size 1.8034 0.508)
			(layers "B.Cu" "B.Mask" "B.Paste")
			(net "GND")
		)
		(pad "247" smd rect
			(at -4.59994 91.799918 270)
			(size 1.8034 0.508)
			(layers "B.Cu" "B.Mask" "B.Paste")
			(net "M_D_DQ<39>")
		)
		(pad "248" smd rect
			(at -4.59994 92.650056 270)
			(size 1.8034 0.508)
			(layers "B.Cu" "B.Mask" "B.Paste")
			(net "GND")
		)
		(pad "249" smd rect
			(at -4.59994 93.49994 270)
			(size 1.8034 0.508)
			(layers "B.Cu" "B.Mask" "B.Paste")
			(net "M_D_DQ<35>")
		)
		(pad "250" smd rect
			(at -4.59994 94.350078 270)
			(size 1.8034 0.508)
			(layers "B.Cu" "B.Mask" "B.Paste")
			(net "GND")
		)
		(pad "251" smd rect
			(at -4.59994 95.199962 270)
			(size 1.8034 0.508)
			(layers "B.Cu" "B.Mask" "B.Paste")
			(net "M_D_DQ<45>")
		)
		(pad "252" smd rect
			(at -4.59994 96.0501 270)
			(size 1.8034 0.508)
			(layers "B.Cu" "B.Mask" "B.Paste")
			(net "GND")
		)
		(pad "253" smd rect
			(at -4.59994 96.899984 270)
			(size 1.8034 0.508)
			(layers "B.Cu" "B.Mask" "B.Paste")
			(net "M_D_DQ<41>")
		)
		(pad "254" smd rect
			(at -4.59994 97.750122 270)
			(size 1.8034 0.508)
			(layers "B.Cu" "B.Mask" "B.Paste")
			(net "GND")
		)
		(pad "255" smd rect
			(at -4.59994 98.600006 270)
			(size 1.8034 0.508)
			(layers "B.Cu" "B.Mask" "B.Paste")
			(net "M_D_DQS_DN<5>")
		)
		(pad "256" smd rect
			(at -4.59994 99.44989 270)
			(size 1.8034 0.508)
			(layers "B.Cu" "B.Mask" "B.Paste")
			(net "M_D_DQS_DP<5>")
		)
		(pad "257" smd rect
			(at -4.59994 100.300028 270)
			(size 1.8034 0.508)
			(layers "B.Cu" "B.Mask" "B.Paste")
			(net "GND")
		)
		(pad "258" smd rect
			(at -4.59994 101.149912 270)
			(size 1.8034 0.508)
			(layers "B.Cu" "B.Mask" "B.Paste")
			(net "M_D_DQ<47>")
		)
		(pad "259" smd rect
			(at -4.59994 102.00005 270)
			(size 1.8034 0.508)
			(layers "B.Cu" "B.Mask" "B.Paste")
			(net "GND")
		)
		(pad "260" smd rect
			(at -4.59994 102.849934 270)
			(size 1.8034 0.508)
			(layers "B.Cu" "B.Mask" "B.Paste")
			(net "M_D_DQ<43>")
		)
		(pad "261" smd rect
			(at -4.59994 103.700072 270)
			(size 1.8034 0.508)
			(layers "B.Cu" "B.Mask" "B.Paste")
			(net "GND")
		)
		(pad "262" smd rect
			(at -4.59994 104.549956 270)
			(size 1.8034 0.508)
			(layers "B.Cu" "B.Mask" "B.Paste")
			(net "M_D_DQ<53>")
		)
		(pad "263" smd rect
			(at -4.59994 105.400094 270)
			(size 1.8034 0.508)
			(layers "B.Cu" "B.Mask" "B.Paste")
			(net "GND")
		)
		(pad "264" smd rect
			(at -4.59994 106.249978 270)
			(size 1.8034 0.508)
			(layers "B.Cu" "B.Mask" "B.Paste")
			(net "M_D_DQ<49>")
		)
		(pad "265" smd rect
			(at -4.59994 107.100116 270)
			(size 1.8034 0.508)
			(layers "B.Cu" "B.Mask" "B.Paste")
			(net "GND")
		)
		(pad "266" smd rect
			(at -4.59994 107.95 270)
			(size 1.8034 0.508)
			(layers "B.Cu" "B.Mask" "B.Paste")
			(net "M_D_DQS_DN<6>")
		)
		(pad "267" smd rect
			(at -4.59994 108.799884 270)
			(size 1.8034 0.508)
			(layers "B.Cu" "B.Mask" "B.Paste")
			(net "M_D_DQS_DP<6>")
		)
		(pad "268" smd rect
			(at -4.59994 109.650022 270)
			(size 1.8034 0.508)
			(layers "B.Cu" "B.Mask" "B.Paste")
			(net "GND")
		)
		(pad "269" smd rect
			(at -4.59994 110.499906 270)
			(size 1.8034 0.508)
			(layers "B.Cu" "B.Mask" "B.Paste")
			(net "M_D_DQ<55>")
		)
		(pad "270" smd rect
			(at -4.59994 111.350044 270)
			(size 1.8034 0.508)
			(layers "B.Cu" "B.Mask" "B.Paste")
			(net "GND")
		)
		(pad "271" smd rect
			(at -4.59994 112.199928 270)
			(size 1.8034 0.508)
			(layers "B.Cu" "B.Mask" "B.Paste")
			(net "M_D_DQ<51>")
		)
		(pad "272" smd rect
			(at -4.59994 113.050066 270)
			(size 1.8034 0.508)
			(layers "B.Cu" "B.Mask" "B.Paste")
			(net "GND")
		)
		(pad "273" smd rect
			(at -4.59994 113.89995 270)
			(size 1.8034 0.508)
			(layers "B.Cu" "B.Mask" "B.Paste")
			(net "M_D_DQ<61>")
		)
		(pad "274" smd rect
			(at -4.59994 114.750088 270)
			(size 1.8034 0.508)
			(layers "B.Cu" "B.Mask" "B.Paste")
			(net "GND")
		)
		(pad "275" smd rect
			(at -4.59994 115.599972 270)
			(size 1.8034 0.508)
			(layers "B.Cu" "B.Mask" "B.Paste")
			(net "M_D_DQ<57>")
		)
		(pad "276" smd rect
			(at -4.59994 116.45011 270)
			(size 1.8034 0.508)
			(layers "B.Cu" "B.Mask" "B.Paste")
			(net "GND")
		)
		(pad "277" smd rect
			(at -4.59994 117.299994 270)
			(size 1.8034 0.508)
			(layers "B.Cu" "B.Mask" "B.Paste")
			(net "M_D_DQS_DN<7>")
		)
		(pad "278" smd rect
			(at -4.59994 118.149878 270)
			(size 1.8034 0.508)
			(layers "B.Cu" "B.Mask" "B.Paste")
			(net "M_D_DQS_DP<7>")
		)
		(pad "279" smd rect
			(at -4.59994 119.000016 270)
			(size 1.8034 0.508)
			(layers "B.Cu" "B.Mask" "B.Paste")
			(net "GND")
		)
		(pad "280" smd rect
			(at -4.59994 119.8499 270)
			(size 1.8034 0.508)
			(layers "B.Cu" "B.Mask" "B.Paste")
			(net "M_D_DQ<63>")
		)
		(pad "281" smd rect
			(at -4.59994 120.700038 270)
			(size 1.8034 0.508)
			(layers "B.Cu" "B.Mask" "B.Paste")
			(net "GND")
		)
		(pad "282" smd rect
			(at -4.59994 121.549922 270)
			(size 1.8034 0.508)
			(layers "B.Cu" "B.Mask" "B.Paste")
			(net "M_D_DQ<59>")
		)
		(pad "283" smd rect
			(at -4.59994 122.40006 270)
			(size 1.8034 0.508)
			(layers "B.Cu" "B.Mask" "B.Paste")
			(net "GND")
		)
		(pad "284" smd rect
			(at -4.59994 123.249944 270)
			(size 1.8034 0.508)
			(layers "B.Cu" "B.Mask" "B.Paste")
			(net "PVPP_DEF")
		)
		(pad "285" smd rect
			(at -4.59994 124.100082 270)
			(size 1.8034 0.508)
			(layers "B.Cu" "B.Mask" "B.Paste")
			(net "SMB_DDR_DEF_VPP_SDA")
		)
		(pad "286" smd rect
			(at -4.59994 124.949966 270)
			(size 1.8034 0.508)
			(layers "B.Cu" "B.Mask" "B.Paste")
			(net "PVPP_DEF")
		)
		(pad "287" smd rect
			(at -4.59994 125.800104 270)
			(size 1.8034 0.508)
			(layers "B.Cu" "B.Mask" "B.Paste")
			(net "PVPP_DEF")
		)
		(pad "288" smd rect
			(at -4.59994 126.649988 270)
			(size 1.8034 0.508)
			(layers "B.Cu" "B.Mask" "B.Paste")
			(net "PVPP_DEF")
		)
	)
)
